FILE_TYPE = CONNECTIVITY;
{Allegro Design Entry HDL 16.6-p007 (v16-6-112F) 10/10/2012}
"PAGE_NUMBER" = 48;
0"NC";
1"M_C_CLK_DN<3:0>";
2"M_C_CLK_DP<3:0>";
3"M_C_CS_N<7:0>";
4"M_C_MA<17:0>";
5"M_C_ECC<7:0>";
6"M_C_CKE<3:0>";
7"M_C_BG<1:0>";
8"M_C_ODT<3:0>";
9"M_C_DQ<63:0>";
10"M_C_DQS_DN<17:0>";
11"M_C_DQS_DP<17:0>";
12"M_C_BA<1:0>";
13"PVTT_ABC\g";
14"PVDDQ_ABC\g";
15"GND\g";
16"GND\g";
17"PVPP_ABC\g";
18"PVPP_ABC\g";
19"GND\g";
20"P12V_NVDIMM_ABC\g";
21"GND\g";
22"M_C_DQ<60>";
23"M_C_DQS_DN<17>";
24"M_C_DQS_DN<16>";
25"M_C_DQ<33>";
26"M_C_MA<5>";
27"M_C_MA<4>";
28"M_C_MA<0>";
29"M_C_BA<1>";
30"M_C_BA<0>";
31"M_C_BG<1>";
32"M_C_DQS_DP<9>";
33"M_C_DQ<45>";
34"M_C_DQ<44>";
35"M_C_DQ<43>";
36"M_C_DQ<42>";
37"M_C_DQ<41>";
38"M_C_DQ<40>";
39"M_C_DQ<38>";
40"M_C_DQS_DN<8>";
41"M_C_DQS_DP<7>";
42"M_C_DQS_DN<2>";
43"M_C_DQS_DN<4>";
44"M_C_DQS_DP<6>";
45"M_C_DQS_DN<5>";
46"M_C_DQ<63>";
47"M_C_DQ<62>";
48"M_C_DQ<55>";
49"M_C_DQS_DN<14>";
50"M_C_DQS_DP<17>";
51"M_C_DQS_DN<9>";
52"M_C_DQS_DP<8>";
53"M_C_DQS_DN<7>";
54"M_C_DQS_DP<16>";
55"M_C_DQS_DP<15>";
56"M_C_DQS_DN<15>";
57"M_C_DQS_DP<14>";
58"M_C_DQS_DP<13>";
59"M_C_DQS_DN<13>";
60"M_C_DQS_DP<12>";
61"M_C_DQS_DN<12>";
62"M_C_DQS_DP<11>";
63"M_C_DQS_DN<11>";
64"M_C_DQS_DP<10>";
65"M_C_DQS_DN<10>";
66"M_C_DQS_DN<6>";
67"M_C_DQS_DP<5>";
68"M_C_DQS_DP<4>";
69"M_C_DQS_DP<3>";
70"M_C_DQS_DN<3>";
71"M_C_DQS_DP<2>";
72"M_C_DQS_DP<1>";
73"M_C_DQS_DN<1>";
74"M_C_DQS_DP<0>";
75"M_C_DQS_DN<0>";
76"M_C_DQ<59>";
77"M_C_DQ<61>";
78"M_C_DQ<48>";
79"M_C_DQ<49>";
80"M_C_DQ<50>";
81"M_C_DQ<51>";
82"M_C_DQ<52>";
83"M_C_DQ<53>";
84"M_C_DQ<54>";
85"M_C_DQ<58>";
86"M_C_DQ<57>";
87"M_C_DQ<56>";
88"M_C_MA<16>";
89"M_C_MA<15>";
90"M_C_MA<14>";
91"M_C_MA<11>";
92"M_C_MA<10>";
93"M_C_MA<2>";
94"M_C_MA<9>";
95"M_C_MA<8>";
96"M_C_MA<7>";
97"M_C_MA<6>";
98"M_C_MA<3>";
99"M_C_MA<17>";
100"M_C_MA<13>";
101"M_C_MA<12>";
102"M_C_DQ<47>";
103"M_C_DQ<39>";
104"M_C_DQ<46>";
105"M_C_DQ<36>";
106"M_C_DQ<35>";
107"M_C_DQ<30>";
108"M_C_DQ<31>";
109"M_C_DQ<32>";
110"M_C_DQ<34>";
111"M_C_DQ<37>";
112"M_C_DQ<28>";
113"M_C_DQ<29>";
114"M_C_DQ<20>";
115"M_C_DQ<26>";
116"M_C_DQ<27>";
117"M_C_DQ<18>";
118"M_C_DQ<19>";
119"M_C_DQ<21>";
120"M_C_DQ<22>";
121"M_C_DQ<23>";
122"M_C_DQ<24>";
123"M_C_DQ<25>";
124"M_C_DQ<11>";
125"M_C_DQ<17>";
126"M_C_DQ<15>";
127"M_C_DQ<7>";
128"M_C_DQ<8>";
129"M_C_DQ<9>";
130"M_C_DQ<10>";
131"M_C_DQ<12>";
132"M_C_DQ<13>";
133"M_C_DQ<14>";
134"M_C_DQ<16>";
135"M_C_DQ<5>";
136"M_C_DQ<4>";
137"M_C_DQ<3>";
138"M_C_DQ<2>";
139"M_C_DQ<0>";
140"M_C_DQ<1>";
141"M_C_DQ<6>";
142"M_C_C<2>";
143"M_C_ACT_N";
144"M_C_ALERT_N";
145"M_C_CLK_DN<2>";
146"M_C_CS_N<7>";
147"M_C_CKE<2>";
148"M_C_ODT<3>";
149"M_C_CS_N<4>";
150"M_C_ODT<2>";
151"M_C_ECC<7>";
152"M_C_BG<0>";
153"M_C_CLK_DP<3>";
154"M_C_CKE<3>";
155"M_C_ECC<0>";
156"M_C_ECC<1>";
157"M_C_ECC<2>";
158"M_C_ECC<3>";
159"M_C_ECC<4>";
160"M_C_ECC<5>";
161"M_C_ECC<6>";
162"M_C_MA<1>";
163"M_C_CS_N<5>";
164"M_C_CS_N<6>";
165"M_C_CLK_DP<2>";
166"M_C_CLK_DN<3>";
167"M_ABC_RST_N";
168"M_C_PAR";
169"FM_DIMM_EVENT_COD_N";
170"FM_ADR_COMPLETE_ABC_N";
171"SMB_DDR_ABC_VPP_SDA";
172"SMB_DDR_ABC_VPP_SCL";
173"TP_CH_C_DIMM_C1_RFU_1";
174"TP_CH_C_DIMM_C1_RFU_0";
175"TP_CH_C_DIMM_C1_RFU_2";
176"M_C_VREF";
%"TAP"
"6","(700,4850)","2","mstr_standard","I10";
;
CDS_LIB"mstr_standard"
BODY_TYPE"PLUMBING"
HDL_TAP"TRUE";
"B \NAC \NWC"11;
"S \NAC"
BN"14"57;
%"TAP"
"6","(-1650,2100)","2","mstr_standard","I100";
;
CDS_LIB"mstr_standard"
BODY_TYPE"PLUMBING"
HDL_TAP"TRUE";
"B \NAC \NWC"9;
"S \NAC"
BN"8"128;
%"TAP"
"6","(-1650,2200)","2","mstr_standard","I101";
;
CDS_LIB"mstr_standard"
BODY_TYPE"PLUMBING"
HDL_TAP"TRUE";
"B \NAC \NWC"9;
"S \NAC"
BN"10"130;
%"TAP"
"6","(-1650,2150)","2","mstr_standard","I102";
;
CDS_LIB"mstr_standard"
BODY_TYPE"PLUMBING"
HDL_TAP"TRUE";
"B \NAC \NWC"9;
"S \NAC"
BN"9"129;
%"TAP"
"6","(-1650,1950)","2","mstr_standard","I103";
;
CDS_LIB"mstr_standard"
BODY_TYPE"PLUMBING"
HDL_TAP"TRUE";
"B \NAC \NWC"9;
"S \NAC"
BN"5"135;
%"TAP"
"6","(-1650,2000)","2","mstr_standard","I104";
;
CDS_LIB"mstr_standard"
BODY_TYPE"PLUMBING"
HDL_TAP"TRUE";
"B \NAC \NWC"9;
"S \NAC"
BN"6"141;
%"TAP"
"6","(-1650,2050)","2","mstr_standard","I105";
;
CDS_LIB"mstr_standard"
BODY_TYPE"PLUMBING"
HDL_TAP"TRUE";
"B \NAC \NWC"9;
"S \NAC"
BN"7"127;
%"TAP"
"6","(-1650,1900)","2","mstr_standard","I106";
;
CDS_LIB"mstr_standard"
BODY_TYPE"PLUMBING"
HDL_TAP"TRUE";
"B \NAC \NWC"9;
"S \NAC"
BN"4"136;
%"TAP"
"6","(-1650,1850)","2","mstr_standard","I107";
;
CDS_LIB"mstr_standard"
BODY_TYPE"PLUMBING"
HDL_TAP"TRUE";
"B \NAC \NWC"9;
"S \NAC"
BN"3"137;
%"TAP"
"6","(-1650,1750)","2","mstr_standard","I108";
;
CDS_LIB"mstr_standard"
BODY_TYPE"PLUMBING"
HDL_TAP"TRUE";
"B \NAC \NWC"9;
"S \NAC"
BN"1"140;
%"TAP"
"6","(-1650,1800)","2","mstr_standard","I109";
;
CDS_LIB"mstr_standard"
BODY_TYPE"PLUMBING"
HDL_TAP"TRUE";
"B \NAC \NWC"9;
"S \NAC"
BN"2"138;
%"TAP"
"6","(-1650,1700)","2","mstr_standard","I110";
;
CDS_LIB"mstr_standard"
BODY_TYPE"PLUMBING"
HDL_TAP"TRUE";
"B \NAC \NWC"9;
"S \NAC"
BN"0"139;
%"SCONN288_H44441003"
"1","(-2400,3200)","0","mstr_sconn","I111";
;
CDS_SEC"1"
PART_NUMBER"H44441-003"
LOCATION"J6U2"
MATERIAL"SCONN"
BOM_SS"NOPOP"
PACK_TYPE"PIP"
BOM_COST"MEM"
CDS_LIB"mstr_sconn"
SEC_TYPE"PIP"
SEC"1"
CDS_LOCATION"J6U2"
ROOM"DDR4_CH_C1";
"DQ<63>"
$PN"280"46;
"BA<1>"
$PN"224"29;
"CK1N"
$PN"219"166;
"CK0P"
$PN"74"165;
"S3_N_C<1>"
$PN"237"146;
"S2_N_C<0>"
$PN"93"164;
"S1_N"
$PN"89"163;
"DQ<29>"
$PN"181"113;
"DQ<28>"
$PN"36"112;
"C<2>"
$PN"235"142;
"A0"
$PN"79"28;
"A1"
$PN"72"162;
"A12"
$PN"65"101;
"A13"
$PN"232"100;
"A17"
$PN"234"99;
"A3"
$PN"71"98;
"A4"
$PN"214"27;
"A5"
$PN"213"26;
"A6"
$PN"69"97;
"A7"
$PN"211"96;
"A8"
$PN"68"95;
"A9"
$PN"66"94;
"CB<6>"
$PN"54"161;
"CB<5>"
$PN"192"160;
"CB<4>"
$PN"47"159;
"CB<3>"
$PN"201"158;
"CB<2>"
$PN"56"157;
"CB<1>"
$PN"194"156;
"CB<0>"
$PN"49"155;
"CK0N"
$PN"75"145;
"CKE<1>"
$PN"203"154;
"DQ<62>"
$PN"135"47;
"DQ<61>"
$PN"273"77;
"DQ<60>"
$PN"128"22;
"DQ<59>"
$PN"282"76;
"DQ<56>"
$PN"130"87;
"DQ<55>"
$PN"269"48;
"DQ<46>"
$PN"113"104;
"DQ<45>"
$PN"251"33;
"DQ<44>"
$PN"106"34;
"DQ<43>"
$PN"260"35;
"DQ<42>"
$PN"115"36;
"DQ<41>"
$PN"253"37;
"DQ<40>"
$PN"108"38;
"DQ<39>"
$PN"247"103;
"DQ<37>"
$PN"240"111;
"DQ<34>"
$PN"104"110;
"DQ<33>"
$PN"242"25;
"DQ<32>"
$PN"97"109;
"DQ<31>"
$PN"188"108;
"DQ<30>"
$PN"43"107;
"DQ<25>"
$PN"183"123;
"DQ<24>"
$PN"38"122;
"DQ<23>"
$PN"177"121;
"DQ<22>"
$PN"32"120;
"DQ<21>"
$PN"170"119;
"DQ<20>"
$PN"25"114;
"DQ<19>"
$PN"179"118;
"DQ<18>"
$PN"34"117;
"DQ<16>"
$PN"27"134;
"DQ<14>"
$PN"21"133;
"DQ<13>"
$PN"159"132;
"DQ<12>"
$PN"14"131;
"DQ<11>"
$PN"168"124;
"DQ<10>"
$PN"23"130;
"DQ<9>"
$PN"161"129;
"DQ<8>"
$PN"16"128;
"DQ<7>"
$PN"155"127;
"DQ<6>"
$PN"10"141;
"EVENT_N"
$PN"78"169;
"PAR"
$PN"222"168;
"RESET_N"
$PN"58"167;
"RFU<2>"
$PN"144"175;
"SCL"
$PN"141"172;
"SDA"
$PN"285"171;
"VREFCA"
$PN"146"176;
"CK1P"
$PN"218"153;
"BG<0>"
$PN"63"152;
"BG<1>"
$PN"207"31;
"BA<0>"
$PN"81"30;
"SA<0>"
$PN"139"18;
"VDDSPD"
$PN"284"18;
"SA<2>"
$PN"238"18;
"SA<1>"
$PN"140"19;
"DQ<1>"
$PN"150"140;
"DQ<0>"
$PN"5"139;
"ACT_N"
$PN"62"143;
"ALERT_N"
$PN"208"144;
"A2"
$PN"216"93;
"DQ<35>"
$PN"249"106;
"DQ<36>"
$PN"95"105;
"DQ<38>"
$PN"102"39;
"A10"
$PN"225"92;
"A11"
$PN"210"91;
"A14_WE_N"
$PN"228"90;
"A15_CAS_N"
$PN"86"89;
"A16_RAS_N"
$PN"82"88;
"CB<7>"
$PN"199"151;
"ODT<0>"
$PN"87"150;
"ODT<1>"
$PN"91"148;
"CKE<0>"
$PN"60"147;
"S0_N"
$PN"84"149;
"DQ<27>"
$PN"190"116;
"DQ<26>"
$PN"45"115;
"DQ<15>"
$PN"166"126;
"DQ<17>"
$PN"172"125;
"RFU<0>"
$PN"205"174;
"RFU<1>"
$PN"227"173;
"SAVE_N_NC"
$PN"230"170;
"DQ<57>"
$PN"275"86;
"DQ<58>"
$PN"137"85;
"DQ<54>"
$PN"124"84;
"DQ<53>"
$PN"262"83;
"DQ<52>"
$PN"117"82;
"DQ<51>"
$PN"271"81;
"DQ<50>"
$PN"126"80;
"DQ<49>"
$PN"264"79;
"DQ<48>"
$PN"119"78;
"DQ<47>"
$PN"258"102;
"DQ<2>"
$PN"12"138;
"DQ<3>"
$PN"157"137;
"DQ<4>"
$PN"3"136;
"DQ<5>"
$PN"148"135;
%"TAP"
"6","(-3150,4850)","0","mstr_standard","I112";
;
CDS_LIB"mstr_standard"
BODY_TYPE"PLUMBING"
HDL_TAP"TRUE";
"B \NAC \NWC"4;
"S \NAC"
BN"17"99;
%"TAP"
"6","(-3150,4800)","0","mstr_standard","I113";
;
CDS_LIB"mstr_standard"
BODY_TYPE"PLUMBING"
HDL_TAP"TRUE";
"B \NAC \NWC"4;
"S \NAC"
BN"16"88;
%"TAP"
"6","(-3150,4750)","0","mstr_standard","I114";
;
CDS_LIB"mstr_standard"
BODY_TYPE"PLUMBING"
HDL_TAP"TRUE";
"B \NAC \NWC"4;
"S \NAC"
BN"15"89;
%"TAP"
"6","(-3150,4700)","0","mstr_standard","I115";
;
CDS_LIB"mstr_standard"
BODY_TYPE"PLUMBING"
HDL_TAP"TRUE";
"B \NAC \NWC"4;
"S \NAC"
BN"14"90;
%"TAP"
"6","(-3150,4650)","0","mstr_standard","I116";
;
CDS_LIB"mstr_standard"
BODY_TYPE"PLUMBING"
HDL_TAP"TRUE";
"B \NAC \NWC"4;
"S \NAC"
BN"13"100;
%"TAP"
"6","(-3150,4600)","0","mstr_standard","I117";
;
CDS_LIB"mstr_standard"
BODY_TYPE"PLUMBING"
HDL_TAP"TRUE";
"B \NAC \NWC"4;
"S \NAC"
BN"12"101;
%"TAP"
"6","(-3150,4550)","0","mstr_standard","I118";
;
CDS_LIB"mstr_standard"
BODY_TYPE"PLUMBING"
HDL_TAP"TRUE";
"B \NAC \NWC"4;
"S \NAC"
BN"11"91;
%"TAP"
"6","(-3150,4500)","0","mstr_standard","I119";
;
CDS_LIB"mstr_standard"
BODY_TYPE"PLUMBING"
HDL_TAP"TRUE";
"B \NAC \NWC"4;
"S \NAC"
BN"10"92;
%"PVTT_ABC"
"1","(-950,2700)","0","mstr_symbols","I12";
;
VOLTAGE"0.6V"
BOM_COST"MEM"
CDS_LIB"mstr_symbols"
BODY_TYPE"PLUMBING"
ROOM"DDR4_CH_B"
HDL_POWER"PVTT_ABC";
"G\NAC"13;
%"TAP"
"6","(-3150,4450)","0","mstr_standard","I120";
;
CDS_LIB"mstr_standard"
BODY_TYPE"PLUMBING"
HDL_TAP"TRUE";
"B \NAC \NWC"4;
"S \NAC"
BN"9"94;
%"TAP"
"6","(-3150,4400)","0","mstr_standard","I121";
;
CDS_LIB"mstr_standard"
BODY_TYPE"PLUMBING"
HDL_TAP"TRUE";
"B \NAC \NWC"4;
"S \NAC"
BN"8"95;
%"TAP"
"6","(-3150,4350)","0","mstr_standard","I122";
;
CDS_LIB"mstr_standard"
BODY_TYPE"PLUMBING"
HDL_TAP"TRUE";
"B \NAC \NWC"4;
"S \NAC"
BN"7"96;
%"TAP"
"6","(-3150,4300)","0","mstr_standard","I123";
;
CDS_LIB"mstr_standard"
BODY_TYPE"PLUMBING"
HDL_TAP"TRUE";
"B \NAC \NWC"4;
"S \NAC"
BN"6"97;
%"TAP"
"6","(-3150,4250)","0","mstr_standard","I124";
;
CDS_LIB"mstr_standard"
BODY_TYPE"PLUMBING"
HDL_TAP"TRUE";
"B \NAC \NWC"4;
"S \NAC"
BN"5"26;
%"TAP"
"6","(-3150,4200)","0","mstr_standard","I125";
;
CDS_LIB"mstr_standard"
BODY_TYPE"PLUMBING"
HDL_TAP"TRUE";
"B \NAC \NWC"4;
"S \NAC"
BN"4"27;
%"TAP"
"6","(-3150,4150)","0","mstr_standard","I126";
;
CDS_LIB"mstr_standard"
BODY_TYPE"PLUMBING"
HDL_TAP"TRUE";
"B \NAC \NWC"4;
"S \NAC"
BN"3"98;
%"TAP"
"6","(-3150,4100)","0","mstr_standard","I128";
;
CDS_LIB"mstr_standard"
BODY_TYPE"PLUMBING"
HDL_TAP"TRUE";
"B \NAC \NWC"4;
"S \NAC"
BN"2"93;
%"TAP"
"6","(-3150,4050)","0","mstr_standard","I129";
;
CDS_LIB"mstr_standard"
BODY_TYPE"PLUMBING"
HDL_TAP"TRUE";
"B \NAC \NWC"4;
"S \NAC"
BN"1"162;
%"PVDDQ_ABC"
"1","(-1150,2550)","0","mstr_symbols","I13";
;
VOLTAGE"1.2V"
BOM_COST"MEM"
CDS_LIB"mstr_symbols"
BODY_TYPE"PLUMBING"
ROOM"DDR4_CH_B"
HDL_POWER"PVDDQ_ABC";
"G\NAC"14;
%"TAP"
"6","(-3150,4000)","0","mstr_standard","I130";
;
CDS_LIB"mstr_standard"
BODY_TYPE"PLUMBING"
HDL_TAP"TRUE";
"B \NAC \NWC"4;
"S \NAC"
BN"0"28;
%"TAP"
"6","(-3150,3900)","0","mstr_standard","I131";
;
CDS_LIB"mstr_standard"
BODY_TYPE"PLUMBING"
HDL_TAP"TRUE";
"B \NAC \NWC"12;
"S \NAC"
BN"1"29;
%"TAP"
"6","(-3150,3850)","0","mstr_standard","I132";
;
CDS_LIB"mstr_standard"
BODY_TYPE"PLUMBING"
HDL_TAP"TRUE";
"B \NAC \NWC"12;
"S \NAC"
BN"0"30;
%"TAP"
"6","(-3150,3750)","0","mstr_standard","I133";
;
CDS_LIB"mstr_standard"
BODY_TYPE"PLUMBING"
HDL_TAP"TRUE";
"B \NAC \NWC"7;
"S \NAC"
BN"0"152;
%"TAP"
"6","(-3150,3800)","0","mstr_standard","I134";
;
CDS_LIB"mstr_standard"
BODY_TYPE"PLUMBING"
HDL_TAP"TRUE";
"B \NAC \NWC"7;
"S \NAC"
BN"1"31;
%"TAP"
"6","(-3150,2800)","0","mstr_standard","I138";
;
CDS_LIB"mstr_standard"
BODY_TYPE"PLUMBING"
HDL_TAP"TRUE";
"B \NAC \NWC"5;
"S \NAC"
BN"7"151;
%"TAP"
"6","(-3150,2750)","0","mstr_standard","I139";
;
CDS_LIB"mstr_standard"
BODY_TYPE"PLUMBING"
HDL_TAP"TRUE";
"B \NAC \NWC"5;
"S \NAC"
BN"6"161;
%"TAP"
"6","(900,4600)","2","mstr_standard","I14";
;
CDS_LIB"mstr_standard"
BODY_TYPE"PLUMBING"
HDL_TAP"TRUE";
"B \NAC \NWC"10;
"S \NAC"
BN"12"61;
%"TAP"
"6","(-3150,2700)","0","mstr_standard","I140";
;
CDS_LIB"mstr_standard"
BODY_TYPE"PLUMBING"
HDL_TAP"TRUE";
"B \NAC \NWC"5;
"S \NAC"
BN"5"160;
%"TAP"
"6","(-3150,2650)","0","mstr_standard","I141";
;
CDS_LIB"mstr_standard"
BODY_TYPE"PLUMBING"
HDL_TAP"TRUE";
"B \NAC \NWC"5;
"S \NAC"
BN"4"159;
%"TAP"
"6","(-3150,2600)","0","mstr_standard","I142";
;
CDS_LIB"mstr_standard"
BODY_TYPE"PLUMBING"
HDL_TAP"TRUE";
"B \NAC \NWC"5;
"S \NAC"
BN"3"158;
%"TAP"
"6","(-3150,2550)","0","mstr_standard","I143";
;
CDS_LIB"mstr_standard"
BODY_TYPE"PLUMBING"
HDL_TAP"TRUE";
"B \NAC \NWC"5;
"S \NAC"
BN"2"157;
%"TAP"
"6","(-3150,2500)","0","mstr_standard","I144";
;
CDS_LIB"mstr_standard"
BODY_TYPE"PLUMBING"
HDL_TAP"TRUE";
"B \NAC \NWC"5;
"S \NAC"
BN"1"156;
%"TAP"
"6","(-3150,2450)","0","mstr_standard","I145";
;
CDS_LIB"mstr_standard"
BODY_TYPE"PLUMBING"
HDL_TAP"TRUE";
"B \NAC \NWC"5;
"S \NAC"
BN"0"155;
%"TAP"
"6","(900,4700)","2","mstr_standard","I15";
;
CDS_LIB"mstr_standard"
BODY_TYPE"PLUMBING"
HDL_TAP"TRUE";
"B \NAC \NWC"10;
"S \NAC"
BN"13"59;
%"TAP"
"6","(-3150,3100)","0","mstr_standard","I152";
;
CDS_LIB"mstr_standard"
BODY_TYPE"PLUMBING"
HDL_TAP"TRUE";
"B \NAC \NWC"6;
"S \NAC"
BN"3"154;
%"TAP"
"6","(-3150,3050)","0","mstr_standard","I154";
;
CDS_LIB"mstr_standard"
BODY_TYPE"PLUMBING"
HDL_TAP"TRUE";
"B \NAC \NWC"6;
"S \NAC"
BN"2"147;
%"TAP"
"6","(-3150,2950)","0","mstr_standard","I155";
;
CDS_LIB"mstr_standard"
BODY_TYPE"PLUMBING"
HDL_TAP"TRUE";
"B \NAC \NWC"8;
"S \NAC"
BN"3"148;
%"TAP"
"6","(-3150,2900)","0","mstr_standard","I157";
;
CDS_LIB"mstr_standard"
BODY_TYPE"PLUMBING"
HDL_TAP"TRUE";
"B \NAC \NWC"8;
"S \NAC"
BN"2"150;
%"TAP"
"6","(-3150,3350)","0","mstr_standard","I158";
;
CDS_LIB"mstr_standard"
BODY_TYPE"PLUMBING"
HDL_TAP"TRUE";
"B \NAC \NWC"3;
"S \NAC"
BN"7"146;
%"TAP"
"6","(-3150,3300)","0","mstr_standard","I159";
;
CDS_LIB"mstr_standard"
BODY_TYPE"PLUMBING"
HDL_TAP"TRUE";
"B \NAC \NWC"3;
"S \NAC"
BN"6"164;
%"TAP"
"6","(700,4750)","2","mstr_standard","I16";
;
CDS_LIB"mstr_standard"
BODY_TYPE"PLUMBING"
HDL_TAP"TRUE";
"B \NAC \NWC"11;
"S \NAC"
BN"13"58;
%"TAP"
"6","(-3150,3250)","0","mstr_standard","I160";
;
CDS_LIB"mstr_standard"
BODY_TYPE"PLUMBING"
HDL_TAP"TRUE";
"B \NAC \NWC"3;
"S \NAC"
BN"5"163;
%"TAP"
"6","(-3150,3200)","0","mstr_standard","I161";
;
CDS_LIB"mstr_standard"
BODY_TYPE"PLUMBING"
HDL_TAP"TRUE";
"B \NAC \NWC"3;
"S \NAC"
BN"4"149;
%"TAP"
"6","(-3150,3650)","0","mstr_standard","I163";
;
CDS_LIB"mstr_standard"
BODY_TYPE"PLUMBING"
HDL_TAP"TRUE";
"B \NAC \NWC"2;
"S \NAC"
BN"3"153;
%"TAP"
"6","(-3150,3550)","0","mstr_standard","I164";
;
CDS_LIB"mstr_standard"
BODY_TYPE"PLUMBING"
HDL_TAP"TRUE";
"B \NAC \NWC"2;
"S \NAC"
BN"2"165;
%"TAP"
"6","(-3350,3600)","0","mstr_standard","I165";
;
CDS_LIB"mstr_standard"
BODY_TYPE"PLUMBING"
HDL_TAP"TRUE";
"B \NAC \NWC"1;
"S \NAC"
BN"3"166;
%"TAP"
"6","(-3350,3500)","0","mstr_standard","I166";
;
CDS_LIB"mstr_standard"
BODY_TYPE"PLUMBING"
HDL_TAP"TRUE";
"B \NAC \NWC"1;
"S \NAC"
BN"2"145;
%"TAP"
"6","(700,4650)","2","mstr_standard","I17";
;
CDS_LIB"mstr_standard"
BODY_TYPE"PLUMBING"
HDL_TAP"TRUE";
"B \NAC \NWC"11;
"S \NAC"
BN"12"60;
%"SCONN288_H44441003"
"4","(-100,2000)","0","mstr_sconn","I171";
;
CDS_SEC"4"
LOCATION"J6U2"
PART_NUMBER"H44441-003"
MATERIAL"SCONN"
BOM_SS"NOPOP"
PACK_TYPE"PIP"
BOM_COST"MEM"
CDS_LIB"mstr_sconn"
SEC_TYPE"PIP"
SEC"4"
CDS_LOCATION"J6U2"
ROOM"DDR4_CH_C1";
"VDD<0>"
$PN"236"14;
"VDD<6>"
$PN"220"14;
"VDD<10>"
$PN"209"14;
"VDD<13>"
$PN"92"14;
"VDD<16>"
$PN"85"14;
"VDD<19>"
$PN"76"14;
"VDD<23>"
$PN"64"14;
"VDD<25>"
$PN"59"14;
"VTT<0>"
$PN"221"13;
"12V<1>"
$PN"1"20;
"12V<0>"
$PN"145"20;
"VDD<24>"
$PN"61"14;
"VDD<22>"
$PN"67"14;
"VDD<21>"
$PN"70"14;
"VDD<20>"
$PN"73"14;
"VDD<18>"
$PN"80"14;
"VDD<17>"
$PN"83"14;
"VDD<15>"
$PN"88"14;
"VDD<14>"
$PN"90"14;
"VDD<12>"
$PN"204"14;
"VDD<11>"
$PN"206"14;
"VDD<9>"
$PN"212"14;
"VDD<8>"
$PN"215"14;
"VDD<7>"
$PN"217"14;
"VDD<5>"
$PN"223"14;
"VDD<4>"
$PN"226"14;
"VDD<3>"
$PN"229"14;
"VDD<2>"
$PN"231"14;
"VDD<1>"
$PN"233"14;
"VPP<4>"
$PN"142"17;
"VPP<3>"
$PN"143"17;
"VPP<2>"
$PN"288"17;
"VPP<1>"
$PN"286"17;
"VPP<0>"
$PN"287"17;
"VTT<1>"
$PN"77"13;
%"GND"
"1","(2500,1300)","2","mstr_symbols","I172";
;
VOLTAGE"0"
CDS_LIB"mstr_symbols"
SIZE"1B"
BOM_COST"MEM"
BODY_TYPE"PLUMBING"
ROOM"DDR4_CH_B"
HDL_POWER"GND";
"A\NAC"15;
%"CAP_A"
"1","(-4650,1500)","2","dev_discrete","I176";
;
LOCATION"C6U17"
VALUE"0.01UF"
PACK_TYPE"0402V"
VOLTAGE"25V"
MATERIAL"X7R"
PART_NUMBER"A36096-045"
TOLERANCE"10%"
CDS_LOCATION"C6U17"
BOM_COST"MEM"
CDS_LIB"dev_discrete"
CDS_SEC"1"
SEC_TYPE"0402V"
SEC"1"
ROOM"DDR4_CH_B";
"B"
$PN"2"16;
"A"
$PN"1"176;
%"GND"
"1","(-4650,1250)","0","mstr_symbols","I177";
;
VOLTAGE"0"
SIZE"1B"
BOM_COST"MEM"
CDS_LIB"mstr_symbols"
BODY_TYPE"PLUMBING"
ROOM"DDR4_CH_B"
HDL_POWER"GND";
"A\NAC"16;
%"PVPP_ABC"
"1","(-800,3000)","0","mstr_symbols","I178";
;
VOLTAGE"2.5V"
BOM_COST"MEM"
CDS_LIB"mstr_symbols"
BODY_TYPE"PLUMBING"
ROOM"DDR4_CH_B"
HDL_POWER"PVPP_ABC";
"G\NAC"17;
%"PVPP_ABC"
"1","(-4650,2250)","0","mstr_symbols","I179";
;
VOLTAGE"2.5V"
BOM_COST"MEM"
CDS_LIB"mstr_symbols"
BODY_TYPE"PLUMBING"
ROOM"DDR4_CH_B"
HDL_POWER"PVPP_ABC";
"G\NAC"18;
%"TAP"
"6","(700,4550)","2","mstr_standard","I18";
;
CDS_LIB"mstr_standard"
BODY_TYPE"PLUMBING"
HDL_TAP"TRUE";
"B \NAC \NWC"11;
"S \NAC"
BN"11"62;
%"GND"
"1","(-4650,1850)","0","mstr_symbols","I184";
;
VOLTAGE"0"
CDS_LIB"mstr_symbols"
BOM_COST"MEM"
SIZE"1B"
BODY_TYPE"PLUMBING"
ROOM"DDR4_CH_B"
HDL_POWER"GND";
"A\NAC"19;
%"P12V_NVDIMM_ABC"
"1","(600,3075)","0","mstr_symbols","I185";
;
VOLTAGE"12.0"
CDS_LIB"mstr_symbols"
BODY_TYPE"PLUMBING"
HDL_POWER"P12V_NVDIMM_ABC";
"G\NAC"20;
%"TAP"
"6","(900,4400)","2","mstr_standard","I19";
;
CDS_LIB"mstr_standard"
BODY_TYPE"PLUMBING"
HDL_TAP"TRUE";
"B \NAC \NWC"10;
"S \NAC"
BN"10"65;
%"TAP"
"6","(900,4500)","2","mstr_standard","I20";
;
CDS_LIB"mstr_standard"
BODY_TYPE"PLUMBING"
HDL_TAP"TRUE";
"B \NAC \NWC"10;
"S \NAC"
BN"11"63;
%"TAP"
"6","(900,4300)","2","mstr_standard","I21";
;
CDS_LIB"mstr_standard"
BODY_TYPE"PLUMBING"
HDL_TAP"TRUE";
"B \NAC \NWC"10;
"S \NAC"
BN"9"51;
%"TAP"
"6","(700,4450)","2","mstr_standard","I22";
;
CDS_LIB"mstr_standard"
BODY_TYPE"PLUMBING"
HDL_TAP"TRUE";
"B \NAC \NWC"11;
"S \NAC"
BN"10"64;
%"TAP"
"6","(700,4350)","2","mstr_standard","I23";
;
CDS_LIB"mstr_standard"
BODY_TYPE"PLUMBING"
HDL_TAP"TRUE";
"B \NAC \NWC"11;
"S \NAC"
BN"9"32;
%"TAP"
"6","(900,4100)","2","mstr_standard","I24";
;
CDS_LIB"mstr_standard"
BODY_TYPE"PLUMBING"
HDL_TAP"TRUE";
"B \NAC \NWC"10;
"S \NAC"
BN"7"53;
%"TAP"
"6","(900,4200)","2","mstr_standard","I25";
;
CDS_LIB"mstr_standard"
BODY_TYPE"PLUMBING"
HDL_TAP"TRUE";
"B \NAC \NWC"10;
"S \NAC"
BN"8"40;
%"TAP"
"6","(700,4250)","2","mstr_standard","I26";
;
CDS_LIB"mstr_standard"
BODY_TYPE"PLUMBING"
HDL_TAP"TRUE";
"B \NAC \NWC"11;
"S \NAC"
BN"8"52;
%"TAP"
"6","(700,4150)","2","mstr_standard","I27";
;
CDS_LIB"mstr_standard"
BODY_TYPE"PLUMBING"
HDL_TAP"TRUE";
"B \NAC \NWC"11;
"S \NAC"
BN"7"41;
%"TAP"
"6","(700,4050)","2","mstr_standard","I28";
;
CDS_LIB"mstr_standard"
BODY_TYPE"PLUMBING"
HDL_TAP"TRUE";
"B \NAC \NWC"11;
"S \NAC"
BN"6"44;
%"TAP"
"6","(900,3900)","2","mstr_standard","I29";
;
CDS_LIB"mstr_standard"
BODY_TYPE"PLUMBING"
HDL_TAP"TRUE";
"B \NAC \NWC"10;
"S \NAC"
BN"5"45;
%"TAP"
"6","(900,5100)","2","mstr_standard","I3";
;
CDS_LIB"mstr_standard"
BODY_TYPE"PLUMBING"
HDL_TAP"TRUE";
"B \NAC \NWC"10;
"S \NAC"
BN"17"23;
%"TAP"
"6","(900,4000)","2","mstr_standard","I30";
;
CDS_LIB"mstr_standard"
BODY_TYPE"PLUMBING"
HDL_TAP"TRUE";
"B \NAC \NWC"10;
"S \NAC"
BN"6"66;
%"TAP"
"6","(900,3800)","2","mstr_standard","I31";
;
CDS_LIB"mstr_standard"
BODY_TYPE"PLUMBING"
HDL_TAP"TRUE";
"B \NAC \NWC"10;
"S \NAC"
BN"4"43;
%"TAP"
"6","(700,3950)","2","mstr_standard","I32";
;
CDS_LIB"mstr_standard"
BODY_TYPE"PLUMBING"
HDL_TAP"TRUE";
"B \NAC \NWC"11;
"S \NAC"
BN"5"67;
%"TAP"
"6","(700,3850)","2","mstr_standard","I33";
;
CDS_LIB"mstr_standard"
BODY_TYPE"PLUMBING"
HDL_TAP"TRUE";
"B \NAC \NWC"11;
"S \NAC"
BN"4"68;
%"TAP"
"6","(700,3750)","2","mstr_standard","I34";
;
CDS_LIB"mstr_standard"
BODY_TYPE"PLUMBING"
HDL_TAP"TRUE";
"B \NAC \NWC"11;
"S \NAC"
BN"3"69;
%"TAP"
"6","(900,3500)","2","mstr_standard","I35";
;
CDS_LIB"mstr_standard"
BODY_TYPE"PLUMBING"
HDL_TAP"TRUE";
"B \NAC \NWC"10;
"S \NAC"
BN"1"73;
%"TAP"
"6","(900,3600)","2","mstr_standard","I36";
;
CDS_LIB"mstr_standard"
BODY_TYPE"PLUMBING"
HDL_TAP"TRUE";
"B \NAC \NWC"10;
"S \NAC"
BN"2"42;
%"TAP"
"6","(900,3700)","2","mstr_standard","I37";
;
CDS_LIB"mstr_standard"
BODY_TYPE"PLUMBING"
HDL_TAP"TRUE";
"B \NAC \NWC"10;
"S \NAC"
BN"3"70;
%"TAP"
"6","(700,3650)","2","mstr_standard","I38";
;
CDS_LIB"mstr_standard"
BODY_TYPE"PLUMBING"
HDL_TAP"TRUE";
"B \NAC \NWC"11;
"S \NAC"
BN"2"71;
%"TAP"
"6","(700,3550)","2","mstr_standard","I39";
;
CDS_LIB"mstr_standard"
BODY_TYPE"PLUMBING"
HDL_TAP"TRUE";
"B \NAC \NWC"11;
"S \NAC"
BN"1"72;
%"TAP"
"6","(700,5150)","2","mstr_standard","I4";
;
CDS_LIB"mstr_standard"
BODY_TYPE"PLUMBING"
HDL_TAP"TRUE";
"B \NAC \NWC"11;
"S \NAC"
BN"17"50;
%"TAP"
"6","(900,3400)","2","mstr_standard","I40";
;
CDS_LIB"mstr_standard"
BODY_TYPE"PLUMBING"
HDL_TAP"TRUE";
"B \NAC \NWC"10;
"S \NAC"
BN"0"75;
%"TAP"
"6","(700,3450)","2","mstr_standard","I41";
;
CDS_LIB"mstr_standard"
BODY_TYPE"PLUMBING"
HDL_TAP"TRUE";
"B \NAC \NWC"11;
"S \NAC"
BN"0"74;
%"SCONN288_H44441003"
"3","(1800,2600)","0","mstr_sconn","I43";
;
CDS_SEC"3"
LOCATION"J6U2"
PART_NUMBER"H44441-003"
MATERIAL"SCONN"
BOM_SS"NOPOP"
PACK_TYPE"PIP"
BOM_COST"MEM"
CDS_LIB"mstr_sconn"
SEC_TYPE"PIP"
SEC"3"
CDS_LOCATION"J6U2"
ROOM"DDR4_CH_C1";
"VSS<46>"
$PN"147"15;
"VSS<45>"
$PN"149"15;
"VSS<87>"
$PN"15"21;
"VSS<86>"
$PN"17"21;
"VSS<85>"
$PN"20"21;
"VSS<84>"
$PN"22"21;
"VSS<83>"
$PN"24"21;
"VSS<82>"
$PN"26"21;
"VSS<81>"
$PN"28"21;
"VSS<80>"
$PN"31"21;
"VSS<79>"
$PN"33"21;
"VSS<78>"
$PN"35"21;
"VSS<77>"
$PN"37"21;
"VSS<76>"
$PN"39"21;
"VSS<75>"
$PN"42"21;
"VSS<74>"
$PN"44"21;
"VSS<73>"
$PN"46"21;
"VSS<72>"
$PN"48"21;
"VSS<71>"
$PN"50"21;
"VSS<70>"
$PN"53"21;
"VSS<69>"
$PN"55"21;
"VSS<68>"
$PN"57"21;
"VSS<67>"
$PN"94"21;
"VSS<66>"
$PN"96"21;
"VSS<65>"
$PN"98"21;
"VSS<64>"
$PN"101"21;
"VSS<63>"
$PN"103"21;
"VSS<62>"
$PN"105"21;
"VSS<61>"
$PN"107"21;
"VSS<60>"
$PN"109"21;
"VSS<59>"
$PN"112"21;
"VSS<58>"
$PN"114"21;
"VSS<57>"
$PN"116"21;
"VSS<56>"
$PN"118"21;
"VSS<55>"
$PN"120"21;
"VSS<54>"
$PN"123"21;
"VSS<53>"
$PN"125"21;
"VSS<52>"
$PN"127"21;
"VSS<51>"
$PN"129"21;
"VSS<50>"
$PN"131"21;
"VSS<49>"
$PN"134"21;
"VSS<48>"
$PN"136"21;
"VSS<47>"
$PN"138"21;
"VSS<44>"
$PN"151"15;
"VSS<43>"
$PN"154"15;
"VSS<42>"
$PN"156"15;
"VSS<41>"
$PN"158"15;
"VSS<40>"
$PN"160"15;
"VSS<39>"
$PN"162"15;
"VSS<38>"
$PN"165"15;
"VSS<37>"
$PN"167"15;
"VSS<36>"
$PN"169"15;
"VSS<35>"
$PN"171"15;
"VSS<34>"
$PN"173"15;
"VSS<33>"
$PN"176"15;
"VSS<32>"
$PN"178"15;
"VSS<31>"
$PN"180"15;
"VSS<30>"
$PN"182"15;
"VSS<29>"
$PN"184"15;
"VSS<28>"
$PN"187"15;
"VSS<27>"
$PN"189"15;
"VSS<26>"
$PN"191"15;
"VSS<25>"
$PN"193"15;
"VSS<24>"
$PN"195"15;
"VSS<23>"
$PN"198"15;
"VSS<22>"
$PN"200"15;
"VSS<21>"
$PN"202"15;
"VSS<20>"
$PN"239"15;
"VSS<19>"
$PN"241"15;
"VSS<18>"
$PN"243"15;
"VSS<17>"
$PN"246"15;
"VSS<16>"
$PN"248"15;
"VSS<15>"
$PN"250"15;
"VSS<14>"
$PN"252"15;
"VSS<13>"
$PN"254"15;
"VSS<12>"
$PN"257"15;
"VSS<11>"
$PN"259"15;
"VSS<10>"
$PN"261"15;
"VSS<9>"
$PN"263"15;
"VSS<8>"
$PN"265"15;
"VSS<7>"
$PN"268"15;
"VSS<6>"
$PN"270"15;
"VSS<5>"
$PN"272"15;
"VSS<4>"
$PN"274"15;
"VSS<3>"
$PN"276"15;
"VSS<2>"
$PN"279"15;
"VSS<1>"
$PN"281"15;
"VSS<0>"
$PN"283"15;
"VSS<88>"
$PN"13"21;
"VSS<89>"
$PN"11"21;
"VSS<90>"
$PN"9"21;
"VSS<91>"
$PN"6"21;
"VSS<92>"
$PN"4"21;
"VSS<93>"
$PN"2"21;
%"GND"
"1","(1100,1300)","2","mstr_symbols","I44";
;
VOLTAGE"0"
CDS_LIB"mstr_symbols"
SIZE"1B"
BOM_COST"MEM"
BODY_TYPE"PLUMBING"
ROOM"DDR4_CH_B"
HDL_POWER"GND";
"A\NAC"21;
%"TAP"
"6","(-1650,4850)","2","mstr_standard","I46";
;
CDS_LIB"mstr_standard"
BODY_TYPE"PLUMBING"
HDL_TAP"TRUE";
"B \NAC \NWC"9;
"S \NAC"
BN"63"46;
%"TAP"
"6","(-1650,4800)","2","mstr_standard","I47";
;
CDS_LIB"mstr_standard"
BODY_TYPE"PLUMBING"
HDL_TAP"TRUE";
"B \NAC \NWC"9;
"S \NAC"
BN"62"47;
%"TAP"
"6","(-1650,4650)","2","mstr_standard","I48";
;
CDS_LIB"mstr_standard"
BODY_TYPE"PLUMBING"
HDL_TAP"TRUE";
"B \NAC \NWC"9;
"S \NAC"
BN"59"76;
%"TAP"
"6","(-1650,4700)","2","mstr_standard","I49";
;
CDS_LIB"mstr_standard"
BODY_TYPE"PLUMBING"
HDL_TAP"TRUE";
"B \NAC \NWC"9;
"S \NAC"
BN"60"22;
%"TAP"
"6","(700,5050)","2","mstr_standard","I5";
;
CDS_LIB"mstr_standard"
BODY_TYPE"PLUMBING"
HDL_TAP"TRUE";
"B \NAC \NWC"11;
"S \NAC"
BN"16"54;
%"TAP"
"6","(-1650,4750)","2","mstr_standard","I50";
;
CDS_LIB"mstr_standard"
BODY_TYPE"PLUMBING"
HDL_TAP"TRUE";
"B \NAC \NWC"9;
"S \NAC"
BN"61"77;
%"TAP"
"6","(-1650,4550)","2","mstr_standard","I51";
;
CDS_LIB"mstr_standard"
BODY_TYPE"PLUMBING"
HDL_TAP"TRUE";
"B \NAC \NWC"9;
"S \NAC"
BN"57"86;
%"TAP"
"6","(-1650,4600)","2","mstr_standard","I52";
;
CDS_LIB"mstr_standard"
BODY_TYPE"PLUMBING"
HDL_TAP"TRUE";
"B \NAC \NWC"9;
"S \NAC"
BN"58"85;
%"TAP"
"6","(-1650,4400)","2","mstr_standard","I53";
;
CDS_LIB"mstr_standard"
BODY_TYPE"PLUMBING"
HDL_TAP"TRUE";
"B \NAC \NWC"9;
"S \NAC"
BN"54"84;
%"TAP"
"6","(-1650,4450)","2","mstr_standard","I54";
;
CDS_LIB"mstr_standard"
BODY_TYPE"PLUMBING"
HDL_TAP"TRUE";
"B \NAC \NWC"9;
"S \NAC"
BN"55"48;
%"TAP"
"6","(-1650,4500)","2","mstr_standard","I55";
;
CDS_LIB"mstr_standard"
BODY_TYPE"PLUMBING"
HDL_TAP"TRUE";
"B \NAC \NWC"9;
"S \NAC"
BN"56"87;
%"TAP"
"6","(-1650,4300)","2","mstr_standard","I56";
;
CDS_LIB"mstr_standard"
BODY_TYPE"PLUMBING"
HDL_TAP"TRUE";
"B \NAC \NWC"9;
"S \NAC"
BN"52"82;
%"TAP"
"6","(-1650,4350)","2","mstr_standard","I57";
;
CDS_LIB"mstr_standard"
BODY_TYPE"PLUMBING"
HDL_TAP"TRUE";
"B \NAC \NWC"9;
"S \NAC"
BN"53"83;
%"TAP"
"6","(-1650,4250)","2","mstr_standard","I58";
;
CDS_LIB"mstr_standard"
BODY_TYPE"PLUMBING"
HDL_TAP"TRUE";
"B \NAC \NWC"9;
"S \NAC"
BN"51"81;
%"TAP"
"6","(-1650,4200)","2","mstr_standard","I59";
;
CDS_LIB"mstr_standard"
BODY_TYPE"PLUMBING"
HDL_TAP"TRUE";
"B \NAC \NWC"9;
"S \NAC"
BN"50"80;
%"TAP"
"6","(900,4900)","2","mstr_standard","I6";
;
CDS_LIB"mstr_standard"
BODY_TYPE"PLUMBING"
HDL_TAP"TRUE";
"B \NAC \NWC"10;
"S \NAC"
BN"15"56;
%"TAP"
"6","(-1650,4150)","2","mstr_standard","I60";
;
CDS_LIB"mstr_standard"
BODY_TYPE"PLUMBING"
HDL_TAP"TRUE";
"B \NAC \NWC"9;
"S \NAC"
BN"49"79;
%"SCONN288_H44441003"
"2","(0,4300)","0","mstr_sconn","I61";
;
CDS_SEC"2"
LOCATION"J6U2"
MATERIAL"SCONN"
PART_NUMBER"H44441-003"
BOM_SS"NOPOP"
PACK_TYPE"PIP"
BOM_COST"MEM"
CDS_LIB"mstr_sconn"
SEC_TYPE"PIP"
SEC"2"
CDS_LOCATION"J6U2"
ROOM"DDR4_CH_C1";
"DQS0N"
$PN"152"75;
"DQS0P"
$PN"153"74;
"DQS10N"
$PN"19"65;
"DQS10P"
$PN"18"64;
"DQS11N"
$PN"30"63;
"DQS11P"
$PN"29"62;
"DQS12N"
$PN"41"61;
"DQS12P"
$PN"40"60;
"DQS13N"
$PN"100"59;
"DQS13P"
$PN"99"58;
"DQS14N"
$PN"111"49;
"DQS14P"
$PN"110"57;
"DQS15N"
$PN"122"56;
"DQS15P"
$PN"121"55;
"DQS16N"
$PN"133"24;
"DQS16P"
$PN"132"54;
"DQS17N"
$PN"52"23;
"DQS17P"
$PN"51"50;
"DQS1N"
$PN"163"73;
"DQS1P"
$PN"164"72;
"DQS2N"
$PN"174"42;
"DQS2P"
$PN"175"71;
"DQS3N"
$PN"185"70;
"DQS3P"
$PN"186"69;
"DQS4N"
$PN"244"43;
"DQS4P"
$PN"245"68;
"DQS5N"
$PN"255"45;
"DQS5P"
$PN"256"67;
"DQS6N"
$PN"266"66;
"DQS6P"
$PN"267"44;
"DQS7N"
$PN"277"53;
"DQS7P"
$PN"278"41;
"DQS8N"
$PN"196"40;
"DQS8P"
$PN"197"52;
"DQS9N"
$PN"8"51;
"DQS9P"
$PN"7"32;
%"TAP"
"6","(-1650,4000)","2","mstr_standard","I62";
;
CDS_LIB"mstr_standard"
BODY_TYPE"PLUMBING"
HDL_TAP"TRUE";
"B \NAC \NWC"9;
"S \NAC"
BN"46"104;
%"TAP"
"6","(-1650,4050)","2","mstr_standard","I63";
;
CDS_LIB"mstr_standard"
BODY_TYPE"PLUMBING"
HDL_TAP"TRUE";
"B \NAC \NWC"9;
"S \NAC"
BN"47"102;
%"TAP"
"6","(-1650,4100)","2","mstr_standard","I64";
;
CDS_LIB"mstr_standard"
BODY_TYPE"PLUMBING"
HDL_TAP"TRUE";
"B \NAC \NWC"9;
"S \NAC"
BN"48"78;
%"TAP"
"6","(-1650,3950)","2","mstr_standard","I65";
;
CDS_LIB"mstr_standard"
BODY_TYPE"PLUMBING"
HDL_TAP"TRUE";
"B \NAC \NWC"9;
"S \NAC"
BN"45"33;
%"TAP"
"6","(-1650,3900)","2","mstr_standard","I66";
;
CDS_LIB"mstr_standard"
BODY_TYPE"PLUMBING"
HDL_TAP"TRUE";
"B \NAC \NWC"9;
"S \NAC"
BN"44"34;
%"TAP"
"6","(-1650,3850)","2","mstr_standard","I67";
;
CDS_LIB"mstr_standard"
BODY_TYPE"PLUMBING"
HDL_TAP"TRUE";
"B \NAC \NWC"9;
"S \NAC"
BN"43"35;
%"TAP"
"6","(-1650,3800)","2","mstr_standard","I68";
;
CDS_LIB"mstr_standard"
BODY_TYPE"PLUMBING"
HDL_TAP"TRUE";
"B \NAC \NWC"9;
"S \NAC"
BN"42"36;
%"TAP"
"6","(-1650,3750)","2","mstr_standard","I69";
;
CDS_LIB"mstr_standard"
BODY_TYPE"PLUMBING"
HDL_TAP"TRUE";
"B \NAC \NWC"9;
"S \NAC"
BN"41"37;
%"TAP"
"6","(900,5000)","2","mstr_standard","I7";
;
CDS_LIB"mstr_standard"
BODY_TYPE"PLUMBING"
HDL_TAP"TRUE";
"B \NAC \NWC"10;
"S \NAC"
BN"16"24;
%"TAP"
"6","(-1650,3650)","2","mstr_standard","I70";
;
CDS_LIB"mstr_standard"
BODY_TYPE"PLUMBING"
HDL_TAP"TRUE";
"B \NAC \NWC"9;
"S \NAC"
BN"39"103;
%"TAP"
"6","(-1650,3700)","2","mstr_standard","I71";
;
CDS_LIB"mstr_standard"
BODY_TYPE"PLUMBING"
HDL_TAP"TRUE";
"B \NAC \NWC"9;
"S \NAC"
BN"40"38;
%"TAP"
"6","(-1650,3500)","2","mstr_standard","I72";
;
CDS_LIB"mstr_standard"
BODY_TYPE"PLUMBING"
HDL_TAP"TRUE";
"B \NAC \NWC"9;
"S \NAC"
BN"36"105;
%"TAP"
"6","(-1650,3550)","2","mstr_standard","I73";
;
CDS_LIB"mstr_standard"
BODY_TYPE"PLUMBING"
HDL_TAP"TRUE";
"B \NAC \NWC"9;
"S \NAC"
BN"37"111;
%"TAP"
"6","(-1650,3600)","2","mstr_standard","I74";
;
CDS_LIB"mstr_standard"
BODY_TYPE"PLUMBING"
HDL_TAP"TRUE";
"B \NAC \NWC"9;
"S \NAC"
BN"38"39;
%"TAP"
"6","(-1650,3400)","2","mstr_standard","I75";
;
CDS_LIB"mstr_standard"
BODY_TYPE"PLUMBING"
HDL_TAP"TRUE";
"B \NAC \NWC"9;
"S \NAC"
BN"34"110;
%"TAP"
"6","(-1650,3450)","2","mstr_standard","I76";
;
CDS_LIB"mstr_standard"
BODY_TYPE"PLUMBING"
HDL_TAP"TRUE";
"B \NAC \NWC"9;
"S \NAC"
BN"35"106;
%"TAP"
"6","(-1650,3350)","2","mstr_standard","I77";
;
CDS_LIB"mstr_standard"
BODY_TYPE"PLUMBING"
HDL_TAP"TRUE";
"B \NAC \NWC"9;
"S \NAC"
BN"33"25;
%"TAP"
"6","(-1650,3300)","2","mstr_standard","I78";
;
CDS_LIB"mstr_standard"
BODY_TYPE"PLUMBING"
HDL_TAP"TRUE";
"B \NAC \NWC"9;
"S \NAC"
BN"32"109;
%"TAP"
"6","(-1650,3250)","2","mstr_standard","I79";
;
CDS_LIB"mstr_standard"
BODY_TYPE"PLUMBING"
HDL_TAP"TRUE";
"B \NAC \NWC"9;
"S \NAC"
BN"31"108;
%"TAP"
"6","(900,4800)","2","mstr_standard","I8";
;
CDS_LIB"mstr_standard"
BODY_TYPE"PLUMBING"
HDL_TAP"TRUE";
"B \NAC \NWC"10;
"S \NAC"
BN"14"49;
%"TAP"
"6","(-1650,3100)","2","mstr_standard","I80";
;
CDS_LIB"mstr_standard"
BODY_TYPE"PLUMBING"
HDL_TAP"TRUE";
"B \NAC \NWC"9;
"S \NAC"
BN"28"112;
%"TAP"
"6","(-1650,3150)","2","mstr_standard","I81";
;
CDS_LIB"mstr_standard"
BODY_TYPE"PLUMBING"
HDL_TAP"TRUE";
"B \NAC \NWC"9;
"S \NAC"
BN"29"113;
%"TAP"
"6","(-1650,3200)","2","mstr_standard","I82";
;
CDS_LIB"mstr_standard"
BODY_TYPE"PLUMBING"
HDL_TAP"TRUE";
"B \NAC \NWC"9;
"S \NAC"
BN"30"107;
%"TAP"
"6","(-1650,3050)","2","mstr_standard","I83";
;
CDS_LIB"mstr_standard"
BODY_TYPE"PLUMBING"
HDL_TAP"TRUE";
"B \NAC \NWC"9;
"S \NAC"
BN"27"116;
%"TAP"
"6","(-1650,3000)","2","mstr_standard","I84";
;
CDS_LIB"mstr_standard"
BODY_TYPE"PLUMBING"
HDL_TAP"TRUE";
"B \NAC \NWC"9;
"S \NAC"
BN"26"115;
%"TAP"
"6","(-1650,2850)","2","mstr_standard","I85";
;
CDS_LIB"mstr_standard"
BODY_TYPE"PLUMBING"
HDL_TAP"TRUE";
"B \NAC \NWC"9;
"S \NAC"
BN"23"121;
%"TAP"
"6","(-1650,2950)","2","mstr_standard","I86";
;
CDS_LIB"mstr_standard"
BODY_TYPE"PLUMBING"
HDL_TAP"TRUE";
"B \NAC \NWC"9;
"S \NAC"
BN"25"123;
%"TAP"
"6","(-1650,2900)","2","mstr_standard","I87";
;
CDS_LIB"mstr_standard"
BODY_TYPE"PLUMBING"
HDL_TAP"TRUE";
"B \NAC \NWC"9;
"S \NAC"
BN"24"122;
%"TAP"
"6","(-1650,2750)","2","mstr_standard","I88";
;
CDS_LIB"mstr_standard"
BODY_TYPE"PLUMBING"
HDL_TAP"TRUE";
"B \NAC \NWC"9;
"S \NAC"
BN"21"119;
%"TAP"
"6","(-1650,2800)","2","mstr_standard","I89";
;
CDS_LIB"mstr_standard"
BODY_TYPE"PLUMBING"
HDL_TAP"TRUE";
"B \NAC \NWC"9;
"S \NAC"
BN"22"120;
%"TAP"
"6","(700,4950)","2","mstr_standard","I9";
;
CDS_LIB"mstr_standard"
BODY_TYPE"PLUMBING"
HDL_TAP"TRUE";
"B \NAC \NWC"11;
"S \NAC"
BN"15"55;
%"TAP"
"6","(-1650,2700)","2","mstr_standard","I90";
;
CDS_LIB"mstr_standard"
BODY_TYPE"PLUMBING"
HDL_TAP"TRUE";
"B \NAC \NWC"9;
"S \NAC"
BN"20"114;
%"TAP"
"6","(-1650,2650)","2","mstr_standard","I91";
;
CDS_LIB"mstr_standard"
BODY_TYPE"PLUMBING"
HDL_TAP"TRUE";
"B \NAC \NWC"9;
"S \NAC"
BN"19"118;
%"TAP"
"6","(-1650,2600)","2","mstr_standard","I92";
;
CDS_LIB"mstr_standard"
BODY_TYPE"PLUMBING"
HDL_TAP"TRUE";
"B \NAC \NWC"9;
"S \NAC"
BN"18"117;
%"TAP"
"6","(-1650,2500)","2","mstr_standard","I93";
;
CDS_LIB"mstr_standard"
BODY_TYPE"PLUMBING"
HDL_TAP"TRUE";
"B \NAC \NWC"9;
"S \NAC"
BN"16"134;
%"TAP"
"6","(-1650,2550)","2","mstr_standard","I94";
;
CDS_LIB"mstr_standard"
BODY_TYPE"PLUMBING"
HDL_TAP"TRUE";
"B \NAC \NWC"9;
"S \NAC"
BN"17"125;
%"TAP"
"6","(-1650,2350)","2","mstr_standard","I95";
;
CDS_LIB"mstr_standard"
BODY_TYPE"PLUMBING"
HDL_TAP"TRUE";
"B \NAC \NWC"9;
"S \NAC"
BN"13"132;
%"TAP"
"6","(-1650,2400)","2","mstr_standard","I96";
;
CDS_LIB"mstr_standard"
BODY_TYPE"PLUMBING"
HDL_TAP"TRUE";
"B \NAC \NWC"9;
"S \NAC"
BN"14"133;
%"TAP"
"6","(-1650,2450)","2","mstr_standard","I97";
;
CDS_LIB"mstr_standard"
BODY_TYPE"PLUMBING"
HDL_TAP"TRUE";
"B \NAC \NWC"9;
"S \NAC"
BN"15"126;
%"TAP"
"6","(-1650,2250)","2","mstr_standard","I98";
;
CDS_LIB"mstr_standard"
BODY_TYPE"PLUMBING"
HDL_TAP"TRUE";
"B \NAC \NWC"9;
"S \NAC"
BN"11"124;
%"TAP"
"6","(-1650,2300)","2","mstr_standard","I99";
;
CDS_LIB"mstr_standard"
BODY_TYPE"PLUMBING"
HDL_TAP"TRUE";
"B \NAC \NWC"9;
"S \NAC"
BN"12"131;
END.
